(kicad_pcb
	(version 20260206)
	(generator "pcbnew")
	(generator_version "10.0")
	(general
		(thickness 1.6)
		(legacy_teardrops no)
	)
	(paper "A4")
	(title_block
		(title "timecard-production-celestica-r4006 — R4006-B0001-02_R01.brd")
		(comment 1 "Time Appliance Project (Time Card) / footprints 347-350 of 1113")
	)
	(layers
		(0 "F.Cu" signal "TOP")
		(4 "In1.Cu" signal "L02_GND1")
		(6 "In2.Cu" signal "L03_SIG1")
		(8 "In3.Cu" signal "L04_GND2")
		(10 "In4.Cu" signal "L05_VCC1")
		(12 "In5.Cu" signal "L06_VCC2")
		(14 "In6.Cu" signal "L07_GND3")
		(16 "In7.Cu" signal "L08_SIG2")
		(18 "In8.Cu" signal "L09_GND4")
		(2 "B.Cu" signal "BOTTOM")
		(9 "F.Adhes" user "F.Adhesive")
		(11 "B.Adhes" user "B.Adhesive")
		(13 "F.Paste" user "Package Geometry/Pastemask Top")
		(15 "B.Paste" user "Package Geometry/Pastemask Bottom")
		(5 "F.SilkS" user "Ref Des/Silkscreen Top")
		(7 "B.SilkS" user "Ref Des/Silkscreen Bottom")
		(1 "F.Mask" user "Board Geometry/Soldermask Top")
		(3 "B.Mask" user "Board Geometry/Soldermask Bottom")
		(17 "Dwgs.User" user "User.Drawings")
		(19 "Cmts.User" user "User.Comments")
		(21 "Eco1.User" user "User.Eco1")
		(23 "Eco2.User" user "User.Eco2")
		(25 "Edge.Cuts" user "Board Geometry/Outline")
		(27 "Margin" user)
		(31 "F.CrtYd" user "Package Geometry/Place Bound Top")
		(29 "B.CrtYd" user "Package Geometry/Place Bound Bottom")
		(35 "F.Fab" user "Ref Des/Assembly Top")
		(33 "B.Fab" user "Ref Des/Assembly Bottom")
	)
	(footprint ""
		(layer "F.Cu")
		(at 4.8514 -39.318692 90)
		(property "Reference" "R385"
			(at 2.337308 0.20955 90)
			(unlocked yes)
			(layer "F.SilkS")
			(effects
				(font
					(size 0.635 0.4064)
					(thickness 0.1524)
				)
			)
		)
		(property "Value" "VAL*"
			(at 0.02032 2.13233 90)
			(unlocked yes)
			(layer "F.Fab")
			(hide yes)
			(effects
				(font
					(size 0.7874 0.5842)
					(thickness 0.1524)
				)
			)
		)
		(property "Tolerance" "TOL*"
			(at 0.044704 3.05435 90)
			(unlocked yes)
			(layer "Cmts.User")
			(hide yes)
			(effects
				(font
					(size 0.7874 0.5842)
					(thickness 0.1524)
				)
			)
		)
		(property "User Part Number" "PARTNUM*"
			(at 0.02032 4.024884 90)
			(unlocked yes)
			(layer "Cmts.User")
			(hide yes)
			(effects
				(font
					(size 0.7874 0.5842)
					(thickness 0.1524)
				)
			)
		)
		(property "Device Type" "RESISTOR-G155-133R0-01,33OHM,1%"
			(at 0.008382 1.210564 90)
			(unlocked yes)
			(layer "F.Fab")
			(hide yes)
			(effects
				(font
					(size 0.7874 0.5842)
					(thickness 0.1524)
				)
			)
		)
		(duplicate_pad_numbers_are_jumpers no)
		(fp_line
			(start 1.143 -0.5588)
			(end -1.143 -0.5588)
			(stroke
				(width 0.1)
				(type default)
			)
			(layer "F.SilkS")
		)
		(fp_line
			(start -1.143 -0.5588)
			(end -1.143 0.5588)
			(stroke
				(width 0.1)
				(type default)
			)
			(layer "F.SilkS")
		)
		(fp_line
			(start 1.143 0.5588)
			(end 1.143 -0.5588)
			(stroke
				(width 0.1)
				(type default)
			)
			(layer "F.SilkS")
		)
		(fp_line
			(start -1.143 0.5588)
			(end 1.143 0.5588)
			(stroke
				(width 0.1)
				(type default)
			)
			(layer "F.SilkS")
		)
		(fp_rect
			(start -1.143 -0.5588)
			(end 1.143 0.5588)
			(stroke
				(width 0)
				(type default)
			)
			(fill no)
			(layer "F.CrtYd")
		)
		(fp_line
			(start 0.508 -0.3048)
			(end -0.508 -0.3048)
			(stroke
				(width 0.1)
				(type default)
			)
			(layer "F.Fab")
		)
		(fp_line
			(start -0.508 -0.3048)
			(end -0.508 0.3048)
			(stroke
				(width 0.1)
				(type default)
			)
			(layer "F.Fab")
		)
		(fp_line
			(start 0.508 0.3048)
			(end 0.508 -0.3048)
			(stroke
				(width 0.1)
				(type default)
			)
			(layer "F.Fab")
		)
		(fp_line
			(start -0.508 0.3048)
			(end 0.508 0.3048)
			(stroke
				(width 0.1)
				(type default)
			)
			(layer "F.Fab")
		)
		(pad "1" smd rect
			(at -0.5334 0 90)
			(size 0.7112 0.6096)
			(layers "F.Cu" "F.Mask" "F.Paste")
			(net "SMA1_LED_BLUE_N")
		)
		(pad "2" smd rect
			(at 0.5334 0 90)
			(size 0.7112 0.6096)
			(layers "F.Cu" "F.Mask" "F.Paste")
			(net "UNNAMED_14_LED4PV14_I265_1")
		)
		(zone
			(layer "F.Cu")
			(hatch none 0.5)
			(connect_pads
				(clearance 0)
			)
			(min_thickness 0.25)
			(keepout
				(tracks not_allowed)
				(vias allowed)
				(pads allowed)
				(copperpour not_allowed)
				(footprints allowed)
			)
			(placement
				(enabled no)
				(sheetname "")
			)
			(fill
				(thermal_gap 0.5)
				(thermal_bridge_width 0.5)
				(island_removal_mode 0)
			)
			(polygon
				(pts
					(xy 4.5466 -39.242492) (xy 5.1562 -39.242492) (xy 5.1562 -39.394892) (xy 4.5466 -39.394892)
				)
			)
		)
		(zone
			(layer "F.Cu")
			(hatch none 0.5)
			(connect_pads
				(clearance 0)
			)
			(min_thickness 0.25)
			(keepout
				(tracks allowed)
				(vias not_allowed)
				(pads allowed)
				(copperpour not_allowed)
				(footprints allowed)
			)
			(placement
				(enabled no)
				(sheetname "")
			)
			(fill
				(thermal_gap 0.5)
				(thermal_bridge_width 0.5)
				(island_removal_mode 0)
			)
			(polygon
				(pts
					(xy 4.5466 -39.242492) (xy 5.1562 -39.242492) (xy 5.1562 -39.394892) (xy 4.5466 -39.394892)
				)
			)
		)
	)
	(footprint ""
		(layer "F.Cu")
		(at 41.8084 -100.7364 90)
		(property "Reference" "U5"
			(at -6.66877 1.4986 0)
			(unlocked yes)
			(layer "F.SilkS")
			(effects
				(font
					(size 0.7874 0.5842)
					(thickness 0.1524)
				)
			)
		)
		(property "Value" ""
			(at 0 0 90)
			(layer "F.Fab")
			(effects
				(font
					(size 1.27 1.27)
				)
			)
		)
		(property "User Part Number" "PARTNUM*"
			(at 0.33782 5.715254 90)
			(unlocked yes)
			(layer "Cmts.User")
			(hide yes)
			(effects
				(font
					(size 0.7874 0.5842)
					(thickness 0.1524)
				)
			)
		)
		(property "Device Type" "TPS54824RNVR_VQFN18-G220-10657A"
			(at 0.33782 4.521454 90)
			(unlocked yes)
			(layer "F.Fab")
			(hide yes)
			(effects
				(font
					(size 0.7874 0.5842)
					(thickness 0.1524)
				)
			)
		)
		(duplicate_pad_numbers_are_jumpers no)
		(fp_line
			(start 2.208784 -2.208784)
			(end 2.208784 2.200148)
			(stroke
				(width 0.1)
				(type default)
			)
			(layer "F.SilkS")
		)
		(fp_line
			(start -2.208784 -2.208784)
			(end 2.208784 -2.208784)
			(stroke
				(width 0.1)
				(type default)
			)
			(layer "F.SilkS")
		)
		(fp_line
			(start 2.208784 2.200148)
			(end -2.208784 2.200148)
			(stroke
				(width 0.1)
				(type default)
			)
			(layer "F.SilkS")
		)
		(fp_line
			(start -2.208784 2.200148)
			(end -2.208784 -2.208784)
			(stroke
				(width 0.1)
				(type default)
			)
			(layer "F.SilkS")
		)
		(fp_poly
			(pts
				(arc
					(start -3.084068 -0.48514)
					(mid -3.084068 -1.50114)
					(end -3.084068 -0.48514)
				)
			)
			(stroke
				(width 0)
				(type default)
			)
			(fill yes)
			(layer "F.SilkS")
		)
		(fp_rect
			(start 2.462784 2.454148)
			(end -2.462784 -2.462784)
			(stroke
				(width 0)
				(type default)
			)
			(fill no)
			(layer "F.CrtYd")
		)
		(fp_line
			(start 1.800098 -1.800098)
			(end 1.800098 1.800098)
			(stroke
				(width 0.1)
				(type default)
			)
			(layer "F.Fab")
		)
		(fp_line
			(start -1.800098 -1.800098)
			(end 1.800098 -1.800098)
			(stroke
				(width 0.1)
				(type default)
			)
			(layer "F.Fab")
		)
		(fp_line
			(start 1.800098 1.800098)
			(end -1.800098 1.800098)
			(stroke
				(width 0.1)
				(type default)
			)
			(layer "F.Fab")
		)
		(fp_line
			(start -1.800098 1.800098)
			(end -1.800098 -1.800098)
			(stroke
				(width 0.1)
				(type default)
			)
			(layer "F.Fab")
		)
		(fp_circle
			(center -3.084068 -0.99314)
			(end -3.084068 -0.48514)
			(stroke
				(width 0.1)
				(type default)
			)
			(fill no)
			(layer "F.Fab")
		)
		(fp_text user "13"
			(at 1.6256 -2.78765 90)
			(unlocked yes)
			(layer "F.SilkS")
			(effects
				(font
					(size 0.635 0.4064)
					(thickness 0.1524)
				)
			)
		)
		(fp_text user "18"
			(at -2.3114 -2.66065 90)
			(unlocked yes)
			(layer "F.SilkS")
			(effects
				(font
					(size 0.635 0.4064)
					(thickness 0.1524)
				)
			)
		)
		(fp_text user "12"
			(at 2.73685 -1.0414 0)
			(unlocked yes)
			(layer "F.SilkS")
			(effects
				(font
					(size 0.635 0.4064)
					(thickness 0.1524)
				)
			)
		)
		(fp_text user "8"
			(at 2.60985 2.1336 0)
			(unlocked yes)
			(layer "F.SilkS")
			(effects
				(font
					(size 0.635 0.4064)
					(thickness 0.1524)
				)
			)
		)
		(fp_text user "5"
			(at -1.65735 2.6924 0)
			(unlocked yes)
			(layer "F.SilkS")
			(effects
				(font
					(size 0.635 0.4064)
					(thickness 0.1524)
				)
			)
		)
		(fp_text user "7"
			(at 1.64465 2.8956 0)
			(unlocked yes)
			(layer "F.SilkS")
			(effects
				(font
					(size 0.635 0.4064)
					(thickness 0.1524)
				)
			)
		)
		(fp_text user "6"
			(at -0.81915 3.1496 0)
			(unlocked yes)
			(layer "F.SilkS")
			(effects
				(font
					(size 0.635 0.4064)
					(thickness 0.1524)
				)
			)
		)
		(fp_text user "18"
			(at -1.44907 -2.8194 0)
			(unlocked yes)
			(layer "F.Fab")
			(effects
				(font
					(size 0.7874 0.5842)
					(thickness 0.1524)
				)
			)
		)
		(fp_text user "13"
			(at 1.59893 -2.6924 0)
			(unlocked yes)
			(layer "F.Fab")
			(effects
				(font
					(size 0.7874 0.5842)
					(thickness 0.1524)
				)
			)
		)
		(fp_text user "12"
			(at 2.61493 -1.6764 0)
			(unlocked yes)
			(layer "F.Fab")
			(effects
				(font
					(size 0.7874 0.5842)
					(thickness 0.1524)
				)
			)
		)
		(fp_text user "5"
			(at -2.33807 1.3716 0)
			(unlocked yes)
			(layer "F.Fab")
			(effects
				(font
					(size 0.7874 0.5842)
					(thickness 0.1524)
				)
			)
		)
		(fp_text user "8"
			(at 2.36093 1.6256 0)
			(unlocked yes)
			(layer "F.Fab")
			(effects
				(font
					(size 0.7874 0.5842)
					(thickness 0.1524)
				)
			)
		)
		(fp_text user "7"
			(at 1.34493 2.2606 0)
			(unlocked yes)
			(layer "F.Fab")
			(effects
				(font
					(size 0.7874 0.5842)
					(thickness 0.1524)
				)
			)
		)
		(fp_text user "6"
			(at -1.57607 2.3876 0)
			(unlocked yes)
			(layer "F.Fab")
			(effects
				(font
					(size 0.7874 0.5842)
					(thickness 0.1524)
				)
			)
		)
		(pad "1" smd rect
			(at -1.649984 -0.94996 90)
			(size 0.6096 0.3048)
			(layers "F.Cu" "F.Mask" "F.Paste")
			(net "XP5R0V_BT")
		)
		(pad "2" smd rect
			(at -1.374902 -0.350012 90)
			(size 1.143 0.4064)
			(layers "F.Cu" "F.Mask" "F.Paste")
			(net "VIN_XP5R0V")
		)
		(pad "3" smd rect
			(at -1.374902 0.299974 90)
			(size 1.143 0.3048)
			(layers "F.Cu" "F.Mask" "F.Paste")
			(net "SG")
		)
		(pad "4" smd rect
			(at -1.374902 0.849884 90)
			(size 1.143 0.3048)
			(layers "F.Cu" "F.Mask" "F.Paste")
			(net "SG")
		)
		(pad "5" smd rect
			(at -1.374902 1.400048 90)
			(size 1.143 0.3048)
			(layers "F.Cu" "F.Mask" "F.Paste")
			(net "SG")
		)
		(pad "6" smd rect
			(at -0.32512 0.599948 90)
			(size 0.2032 2.6924)
			(layers "F.Cu" "F.Mask" "F.Paste")
			(net "XP5R0V_SW")
		)
		(pad "7" smd rect
			(at 0.32512 0.599948 90)
			(size 0.2032 2.6924)
			(layers "F.Cu" "F.Mask" "F.Paste")
			(net "XP5R0V_SW")
		)
		(pad "8" smd rect
			(at 1.374902 1.400048 90)
			(size 1.143 0.3048)
			(layers "F.Cu" "F.Mask" "F.Paste")
			(net "SG")
		)
		(pad "9" smd rect
			(at 1.374902 0.849884 90)
			(size 1.143 0.3048)
			(layers "F.Cu" "F.Mask" "F.Paste")
			(net "SG")
		)
		(pad "10" smd rect
			(at 1.374902 0.299974 90)
			(size 1.143 0.3048)
			(layers "F.Cu" "F.Mask" "F.Paste")
			(net "SG")
		)
		(pad "11" smd rect
			(at 1.374902 -0.350012 90)
			(size 1.143 0.4064)
			(layers "F.Cu" "F.Mask" "F.Paste")
			(net "VIN_XP5R0V")
		)
		(pad "12" smd rect
			(at 1.649984 -0.94996 90)
			(size 0.6096 0.3048)
			(layers "F.Cu" "F.Mask" "F.Paste")
			(net "XP5R0V_AGND")
		)
		(pad "13" smd rect
			(at 1.374902 -1.649984 90)
			(size 0.508 0.6096)
			(layers "F.Cu" "F.Mask" "F.Paste")
			(net "XP5R0V_RT")
		)
		(pad "14" smd rect
			(at 0.750062 -1.649984 90)
			(size 0.254 0.6096)
			(layers "F.Cu" "F.Mask" "F.Paste")
			(net "XP5R0V_FB_R_TO_AGND")
		)
		(pad "15" smd rect
			(at 0.249936 -1.649984 90)
			(size 0.254 0.6096)
			(layers "F.Cu" "F.Mask" "F.Paste")
			(net "XP5R0V_COMP")
		)
		(pad "16" smd rect
			(at -0.249936 -1.649984 90)
			(size 0.254 0.6096)
			(layers "F.Cu" "F.Mask" "F.Paste")
			(net "XP5R0V_SS")
		)
		(pad "17" smd rect
			(at -0.750062 -1.649984 90)
			(size 0.254 0.6096)
			(layers "F.Cu" "F.Mask" "F.Paste")
			(net "R_XP5R0V_EN")
		)
		(pad "18" smd rect
			(at -1.374902 -1.649984 90)
			(size 0.508 0.6096)
			(layers "F.Cu" "F.Mask" "F.Paste")
			(net "XP5R0V_PG")
		)
	)
	(footprint ""
		(layer "F.Cu")
		(at 117.346984 -41.32326)
		(property "Reference" "TP140"
			(at 0 0 0)
			(layer "F.SilkS")
			(hide yes)
			(effects
				(font
					(size 1.27 1.27)
				)
			)
		)
		(property "Value" ""
			(at 0 0 0)
			(layer "F.Fab")
			(effects
				(font
					(size 1.27 1.27)
				)
			)
		)
		(property "Device Type" "TP_PIONT-TP010CT020B030_PTH-TPA"
			(at -1.341882 0.996696 0)
			(unlocked yes)
			(layer "F.Fab")
			(hide yes)
			(effects
				(font
					(size 0.7874 0.5842)
					(thickness 0.1524)
				)
				(justify left)
			)
		)
		(duplicate_pad_numbers_are_jumpers no)
		(fp_poly
			(pts
				(arc
					(start 0.889 0)
					(mid -0.889 0)
					(end 0.889 0)
				)
			)
			(stroke
				(width 0)
				(type default)
			)
			(fill no)
			(layer "B.CrtYd")
		)
		(fp_poly
			(pts
				(arc
					(start 0.889 0)
					(mid -0.889 0)
					(end 0.889 0)
				)
			)
			(stroke
				(width 0)
				(type default)
			)
			(fill no)
			(layer "F.CrtYd")
		)
		(pad "1" thru_hole circle
			(at 0 0)
			(size 0.508 0.508)
			(drill 0.254)
			(layers "*.Cu" "*.Mask")
			(remove_unused_layers no)
			(net "IO_L24P_34")
			(clearance 0.1016)
			(padstack
				(mode front_inner_back)
				(layer "Inner"
					(shape circle)
					(size 0.508 0.508)
					(clearance 0.1016)
				)
				(layer "B.Cu"
					(shape circle)
					(size 0.762 0.762)
					(clearance -0.0254)
				)
			)
		)
	)
	(footprint ""
		(layer "F.Cu")
		(at 145.8214 -96.6978)
		(property "Reference" "C5"
			(at 2.667 -0.59563 0)
			(unlocked yes)
			(layer "F.SilkS")
			(effects
				(font
					(size 0.7874 0.5842)
					(thickness 0.1524)
				)
			)
		)
		(property "Value" "VAL*"
			(at 0.0762 2.067306 0)
			(unlocked yes)
			(layer "F.Fab")
			(hide yes)
			(effects
				(font
					(size 0.7874 0.5842)
					(thickness 0.1524)
				)
			)
		)
		(property "Device Type" "CAPACITOR-G105-0B104-EK,0.1UF,A"
			(at 0.0508 1.127506 0)
			(unlocked yes)
			(layer "F.Fab")
			(hide yes)
			(effects
				(font
					(size 0.7874 0.5842)
					(thickness 0.1524)
				)
			)
		)
		(property "User Part Number" "PARTNUM*"
			(at 0.1016 4.023106 0)
			(unlocked yes)
			(layer "Cmts.User")
			(hide yes)
			(effects
				(font
					(size 0.7874 0.5842)
					(thickness 0.1524)
				)
			)
		)
		(property "Tolerance" "TOL*"
			(at 0.0762 3.032506 0)
			(unlocked yes)
			(layer "Cmts.User")
			(hide yes)
			(effects
				(font
					(size 0.7874 0.5842)
					(thickness 0.1524)
				)
			)
		)
		(duplicate_pad_numbers_are_jumpers no)
		(fp_line
			(start -1.143 -0.5588)
			(end -1.143 0.5588)
			(stroke
				(width 0.1)
				(type default)
			)
			(layer "F.SilkS")
		)
		(fp_line
			(start -1.143 0.5588)
			(end 1.143 0.5588)
			(stroke
				(width 0.1)
				(type default)
			)
			(layer "F.SilkS")
		)
		(fp_line
			(start 1.143 -0.5588)
			(end -1.143 -0.5588)
			(stroke
				(width 0.1)
				(type default)
			)
			(layer "F.SilkS")
		)
		(fp_line
			(start 1.143 0.5588)
			(end 1.143 -0.5588)
			(stroke
				(width 0.1)
				(type default)
			)
			(layer "F.SilkS")
		)
		(fp_rect
			(start -1.143 0.5588)
			(end 1.143 -0.5588)
			(stroke
				(width 0)
				(type default)
			)
			(fill no)
			(layer "F.CrtYd")
		)
		(fp_line
			(start -0.508 -0.3048)
			(end -0.508 0.3048)
			(stroke
				(width 0.1)
				(type default)
			)
			(layer "F.Fab")
		)
		(fp_line
			(start -0.508 0.3048)
			(end 0.508 0.3048)
			(stroke
				(width 0.1)
				(type default)
			)
			(layer "F.Fab")
		)
		(fp_line
			(start 0.508 -0.3048)
			(end -0.508 -0.3048)
			(stroke
				(width 0.1)
				(type default)
			)
			(layer "F.Fab")
		)
		(fp_line
			(start 0.508 0.3048)
			(end 0.508 -0.3048)
			(stroke
				(width 0.1)
				(type default)
			)
			(layer "F.Fab")
		)
		(pad "1" smd rect
			(at -0.5334 0)
			(size 0.7112 0.6096)
			(layers "F.Cu" "F.Mask" "F.Paste")
			(net "XP12R0V_A_SS")
		)
		(pad "2" smd rect
			(at 0.5334 0)
			(size 0.7112 0.6096)
			(layers "F.Cu" "F.Mask" "F.Paste")
			(net "SG")
		)
		(zone
			(layer "F.Cu")
			(hatch none 0.5)
			(connect_pads
				(clearance 0)
			)
			(min_thickness 0.25)
			(keepout
				(tracks allowed)
				(vias not_allowed)
				(pads allowed)
				(copperpour not_allowed)
				(footprints allowed)
			)
			(placement
				(enabled no)
				(sheetname "")
			)
			(fill
				(thermal_gap 0.5)
				(thermal_bridge_width 0.5)
				(island_removal_mode 0)
			)
			(polygon
				(pts
					(xy 145.7452 -96.393) (xy 145.8976 -96.393) (xy 145.8976 -97.0026) (xy 145.7452 -97.0026)
				)
			)
		)
	)
)
